# S9S_MB_2U (Grand Teton) — schematic netlist excerpt (pin names and nets, part order shuffled) for the footprints in the layout excerpt that follows; sources: Cadence DE-HDL packaged netlist, KiCad conversion of 03242023_DA0F0TMBIJ0_F0T_Motherboard_J_brd_V01_OCP.brd

C527  Q_CAP  47UF 4V 20% X6S  pkg C0805  page 75 : A = PVCCIN_CPU0 ; B = GND
R1505  Q_RES  33.2 1% CHIP  pkg 0402LF  page 155 : A = RST_OCP_V3_1_BUF_N ; B = RST_PERST3_OCP_SFF_N
R46  Q_RES  54.9K 1% CHIP  pkg 0402LF  page 102 : A = PD_CHC_CPU1_DIMM1_SAA ; B = GND

(kicad_pcb
	(version 20260206)
	(generator "pcbnew")
	(generator_version "10.0")
	(general
		(thickness 1.6)
		(legacy_teardrops no)
	)
	(paper "A4")
	(title_block
		(title "03242023_DA0F0TMBIJ0_F0T_Motherboard_J_brd_V01_OCP.brd")
		(comment 1 "Grand Teton / footprints 5650-5652 of 6105")
	)
	(layers
		(0 "F.Cu" signal "TOP")
		(4 "In1.Cu" signal "GND")
		(6 "In2.Cu" signal "IN1")
		(8 "In3.Cu" signal "GND1")
		(10 "In4.Cu" signal "IN2")
		(12 "In5.Cu" signal "GND2")
		(14 "In6.Cu" signal "IN3")
		(16 "In7.Cu" signal "GND3")
		(18 "In8.Cu" signal "VCC")
		(20 "In9.Cu" signal "VCC1")
		(22 "In10.Cu" signal "GND4")
		(24 "In11.Cu" signal "IN4")
		(26 "In12.Cu" signal "GND5")
		(28 "In13.Cu" signal "IN5")
		(30 "In14.Cu" signal "GND6")
		(32 "In15.Cu" signal "IN6")
		(34 "In16.Cu" signal "GND7")
		(2 "B.Cu" signal "BOTTOM")
		(9 "F.Adhes" user "F.Adhesive")
		(11 "B.Adhes" user "B.Adhesive")
		(13 "F.Paste" user "Package Geometry/Pastemask Top")
		(15 "B.Paste" user "Package Geometry/Pastemask Bottom")
		(5 "F.SilkS" user "Ref Des/Silkscreen Top")
		(7 "B.SilkS" user "Ref Des/Silkscreen Bottom")
		(1 "F.Mask" user "Board Geometry/Soldermask Top")
		(3 "B.Mask" user "Board Geometry/Soldermask Bottom")
		(17 "Dwgs.User" user "User.Drawings")
		(19 "Cmts.User" user "User.Comments")
		(21 "Eco1.User" user "User.Eco1")
		(23 "Eco2.User" user "User.Eco2")
		(25 "Edge.Cuts" user "Board Geometry/Outline")
		(27 "Margin" user)
		(31 "F.CrtYd" user "Package Geometry/Place Bound Top")
		(29 "B.CrtYd" user "Package Geometry/Place Bound Bottom")
		(35 "F.Fab" user "Ref Des/Assembly Top")
		(33 "B.Fab" user "Ref Des/Assembly Bottom")
	)
	(footprint ""
		(layer "B.Cu")
		(at 25.072848 -318.633856)
		(property "Reference" "R46"
			(at 0 0 0)
			(layer "B.SilkS")
			(hide yes)
			(effects
				(font
					(size 1.27 1.27)
				)
				(justify mirror)
			)
		)
		(property "Value" ""
			(at 0 0 0)
			(layer "B.Fab")
			(effects
				(font
					(size 1.27 1.27)
				)
				(justify mirror)
			)
		)
		(duplicate_pad_numbers_are_jumpers no)
		(fp_line
			(start -0.7874 -0.4064)
			(end -0.7874 0.4064)
			(stroke
				(width 0.1524)
				(type default)
			)
			(layer "B.SilkS")
		)
		(fp_line
			(start -0.7874 0.4064)
			(end 0.7874 0.4064)
			(stroke
				(width 0.1524)
				(type default)
			)
			(layer "B.SilkS")
		)
		(fp_line
			(start 0.7874 -0.4064)
			(end -0.7874 -0.4064)
			(stroke
				(width 0.1524)
				(type default)
			)
			(layer "B.SilkS")
		)
		(fp_line
			(start 0.7874 0.4064)
			(end 0.7874 -0.4064)
			(stroke
				(width 0.1524)
				(type default)
			)
			(layer "B.SilkS")
		)
		(fp_line
			(start -0.67945 -0.3048)
			(end -0.67945 0.3048)
			(stroke
				(width 0.1)
				(type default)
			)
			(layer "B.Fab")
		)
		(fp_line
			(start -0.67945 0.3048)
			(end -0.120396 0.3048)
			(stroke
				(width 0.1)
				(type default)
			)
			(layer "B.Fab")
		)
		(fp_line
			(start -0.12065 -0.3048)
			(end -0.67945 -0.3048)
			(stroke
				(width 0.1)
				(type default)
			)
			(layer "B.Fab")
		)
		(fp_line
			(start -0.12065 -0.2794)
			(end -0.12065 -0.3048)
			(stroke
				(width 0.1)
				(type default)
			)
			(layer "B.Fab")
		)
		(fp_line
			(start -0.120396 0.2794)
			(end 0.12065 0.2794)
			(stroke
				(width 0.1)
				(type default)
			)
			(layer "B.Fab")
		)
		(fp_line
			(start -0.120396 0.3048)
			(end -0.120396 0.2794)
			(stroke
				(width 0.1)
				(type default)
			)
			(layer "B.Fab")
		)
		(fp_line
			(start 0.12065 -0.305054)
			(end 0.12065 -0.2794)
			(stroke
				(width 0.1)
				(type default)
			)
			(layer "B.Fab")
		)
		(fp_line
			(start 0.12065 -0.2794)
			(end -0.12065 -0.2794)
			(stroke
				(width 0.1)
				(type default)
			)
			(layer "B.Fab")
		)
		(fp_line
			(start 0.12065 0.2794)
			(end 0.12065 0.3048)
			(stroke
				(width 0.1)
				(type default)
			)
			(layer "B.Fab")
		)
		(fp_line
			(start 0.12065 0.3048)
			(end 0.67945 0.3048)
			(stroke
				(width 0.1)
				(type default)
			)
			(layer "B.Fab")
		)
		(fp_line
			(start 0.67945 -0.305054)
			(end 0.12065 -0.305054)
			(stroke
				(width 0.1)
				(type default)
			)
			(layer "B.Fab")
		)
		(fp_line
			(start 0.67945 0.3048)
			(end 0.67945 -0.305054)
			(stroke
				(width 0.1)
				(type default)
			)
			(layer "B.Fab")
		)
		(pad "1" smd circle
			(at 0.40005 0 180)
			(size 0 0)
			(layers "B.Cu" "B.Mask" "B.Paste")
			(net "PD_CHC_CPU1_DIMM1_SAA")
		)
		(pad "2" smd circle
			(at -0.40005 0 180)
			(size 0 0)
			(layers "B.Cu" "B.Mask" "B.Paste")
			(net "GND")
		)
	)
	(footprint ""
		(layer "B.Cu")
		(at 353.658678 -241.13871 90)
		(property "Reference" "C527"
			(at 0 0 90)
			(layer "B.SilkS")
			(hide yes)
			(effects
				(font
					(size 1.27 1.27)
				)
				(justify mirror)
			)
		)
		(property "Value" ""
			(at 0 0 90)
			(layer "B.Fab")
			(effects
				(font
					(size 1.27 1.27)
				)
				(justify mirror)
			)
		)
		(duplicate_pad_numbers_are_jumpers no)
		(fp_line
			(start 1.524 -0.762)
			(end -1.524 -0.762)
			(stroke
				(width 0.1524)
				(type default)
			)
			(layer "B.SilkS")
		)
		(fp_line
			(start -1.524 -0.762)
			(end -1.524 0.762)
			(stroke
				(width 0.1524)
				(type default)
			)
			(layer "B.SilkS")
		)
		(fp_line
			(start 1.524 0.762)
			(end 1.524 -0.762)
			(stroke
				(width 0.1524)
				(type default)
			)
			(layer "B.SilkS")
		)
		(fp_line
			(start -1.524 0.762)
			(end 1.524 0.762)
			(stroke
				(width 0.1524)
				(type default)
			)
			(layer "B.SilkS")
		)
		(fp_line
			(start 1.1049 -0.724916)
			(end 1.1049 0.724916)
			(stroke
				(width 0.1)
				(type default)
			)
			(layer "B.Fab")
		)
		(fp_line
			(start -1.1049 -0.724916)
			(end 1.1049 -0.724916)
			(stroke
				(width 0.1)
				(type default)
			)
			(layer "B.Fab")
		)
		(fp_line
			(start 1.1049 0.724916)
			(end -1.1049 0.724916)
			(stroke
				(width 0.1)
				(type default)
			)
			(layer "B.Fab")
		)
		(fp_line
			(start -1.1049 0.724916)
			(end -1.1049 -0.724916)
			(stroke
				(width 0.1)
				(type default)
			)
			(layer "B.Fab")
		)
		(pad "1" smd rect
			(at 0.889 0 90)
			(size 1.016 1.27)
			(layers "B.Cu" "B.Mask" "B.Paste")
			(net "PVCCIN_CPU0")
		)
		(pad "2" smd rect
			(at -0.889 0 90)
			(size 1.016 1.27)
			(layers "B.Cu" "B.Mask" "B.Paste")
			(net "GND")
		)
	)
	(footprint ""
		(layer "B.Cu")
		(at 450.70649 -3.871468 -90)
		(property "Reference" "R1505"
			(at 0 0 90)
			(layer "B.SilkS")
			(hide yes)
			(effects
				(font
					(size 1.27 1.27)
				)
				(justify mirror)
			)
		)
		(property "Value" ""
			(at 0 0 90)
			(layer "B.Fab")
			(effects
				(font
					(size 1.27 1.27)
				)
				(justify mirror)
			)
		)
		(duplicate_pad_numbers_are_jumpers no)
		(fp_line
			(start -0.7874 0.4064)
			(end 0.7874 0.4064)
			(stroke
				(width 0.1524)
				(type default)
			)
			(layer "B.SilkS")
		)
		(fp_line
			(start 0.7874 0.4064)
			(end 0.7874 -0.4064)
			(stroke
				(width 0.1524)
				(type default)
			)
			(layer "B.SilkS")
		)
		(fp_line
			(start -0.7874 -0.4064)
			(end -0.7874 0.4064)
			(stroke
				(width 0.1524)
				(type default)
			)
			(layer "B.SilkS")
		)
		(fp_line
			(start 0.7874 -0.4064)
			(end -0.7874 -0.4064)
			(stroke
				(width 0.1524)
				(type default)
			)
			(layer "B.SilkS")
		)
		(fp_line
			(start -0.67945 0.3048)
			(end -0.120396 0.3048)
			(stroke
				(width 0.1)
				(type default)
			)
			(layer "B.Fab")
		)
		(fp_line
			(start -0.120396 0.3048)
			(end -0.120396 0.2794)
			(stroke
				(width 0.1)
				(type default)
			)
			(layer "B.Fab")
		)
		(fp_line
			(start 0.12065 0.3048)
			(end 0.67945 0.3048)
			(stroke
				(width 0.1)
				(type default)
			)
			(layer "B.Fab")
		)
		(fp_line
			(start 0.67945 0.3048)
			(end 0.67945 -0.305054)
			(stroke
				(width 0.1)
				(type default)
			)
			(layer "B.Fab")
		)
		(fp_line
			(start -0.120396 0.2794)
			(end 0.12065 0.2794)
			(stroke
				(width 0.1)
				(type default)
			)
			(layer "B.Fab")
		)
		(fp_line
			(start 0.12065 0.2794)
			(end 0.12065 0.3048)
			(stroke
				(width 0.1)
				(type default)
			)
			(layer "B.Fab")
		)
		(fp_line
			(start -0.12065 -0.2794)
			(end -0.12065 -0.3048)
			(stroke
				(width 0.1)
				(type default)
			)
			(layer "B.Fab")
		)
		(fp_line
			(start 0.12065 -0.2794)
			(end -0.12065 -0.2794)
			(stroke
				(width 0.1)
				(type default)
			)
			(layer "B.Fab")
		)
		(fp_line
			(start -0.67945 -0.3048)
			(end -0.67945 0.3048)
			(stroke
				(width 0.1)
				(type default)
			)
			(layer "B.Fab")
		)
		(fp_line
			(start -0.12065 -0.3048)
			(end -0.67945 -0.3048)
			(stroke
				(width 0.1)
				(type default)
			)
			(layer "B.Fab")
		)
		(fp_line
			(start 0.12065 -0.305054)
			(end 0.12065 -0.2794)
			(stroke
				(width 0.1)
				(type default)
			)
			(layer "B.Fab")
		)
		(fp_line
			(start 0.67945 -0.305054)
			(end 0.12065 -0.305054)
			(stroke
				(width 0.1)
				(type default)
			)
			(layer "B.Fab")
		)
		(pad "1" smd circle
			(at 0.40005 0 90)
			(size 0 0)
			(layers "B.Cu" "B.Mask" "B.Paste")
			(net "RST_OCP_V3_1_BUF_N")
		)
		(pad "2" smd circle
			(at -0.40005 0 90)
			(size 0 0)
			(layers "B.Cu" "B.Mask" "B.Paste")
			(net "RST_PERST3_OCP_SFF_N")
		)
	)
)
